FILE_TYPE = CONNECTIVITY;
{Allegro Design Entry HDL 17.2-2016 S081 (4005846) 1/11/2022}
"PAGE_NUMBER" = 160;
0"NC";
1"P3V3_AUX\g";
2"P3V3_AUX\g";
3"P3V3_AUX\g";
4"P3V3_AUX\g";
5"P3V3_AUX\g";
6"P3V3_AUX\g";
7"P3V3_AUX\g";
8"P3V3_AUX\g";
9"P3V3_AUX\g";
10"GND\g";
11"GND\g";
12"GND\g";
13"GND\g";
14"GND\g";
15"GND\g";
16"GND\g";
17"GND\g";
18"GND\g";
19"GND\g";
20"GND\g";
21"GND\g";
22"GND\g";
23"GND\g";
24"GND\g";
25"GPU_FPGA_BOOT_EN_BUF";
26"GPU_FPGA_BOOT_EN_BUF_R";
27"GPU_BASE_STBY_EN_BUF_R";
28"GPU_BASE_STBY_EN_BUF";
29"RST_PERST_0_SWB_BUF_N";
30"RST_PERST_1_SWB_BUF_R_N";
31"RST_PERST_1_SWB_BUF_N";
32"RST_PERST_0_SWB_BUF_R_N";
33"FM_SWB_PWR_EN_R_BUF";
34"FM_SWB_PWR_EN_R1_BUF";
35"RST_PERST_2_SWB_BUF_R_N";
36"RST_PERST_2_SWB_BUF_N";
37"RST_PERST_SWB_R_N";
38"GPU_FPGA_BOOT_EN";
39"GPU_BASE_STBY_EN";
40"FM_SWB_PWR_EN_R";
%"Q_RES"
"2","(-4950,2725)","0","pure_quanta","I123";
;
PART_NUMBER"CS31002FB08"
VALUE"10K"
TOLERANCE"1%"
MATERIAL"CHIP"
WATTAGE"1/16W"
PACK_TYPE"0402LF"
$LOCATION"R3457"
CDS_LIB"pure_quanta"
CDS_LOCATION"R3457"
$SEC"1"
CDS_SEC"1";
"A"
$PN"1"27;
"B"
$PN"2"22;
%"Q_RES"
"2","(-4975,3225)","0","pure_quanta","I124";
;
PART_NUMBER"CS41002FB09"
MATERIAL"EMPTY"
WATTAGE"1/16W"
TOLERANCE"1%"
VALUE"100K"
PACK_TYPE"0402LF"
$LOCATION"R3456"
CDS_LIB"pure_quanta"
CDS_LOCATION"R3456"
$SEC"1"
CDS_SEC"1";
"A"
$PN"1"1;
"B"
$PN"2"27;
%"UNIVERSAL_POWER"
"1","(-4975,3525)","0","logical_power","I125";
;
HDL_POWER"P3V3_AUX"
CDS_LIB"logical_power";
"A"1;
%"UNIVERSAL_GND"
"1","(-4950,2500)","0","logical_power","I126";
;
HDL_POWER"GND"
CDS_LIB"logical_power";
"A"22;
%"Q_RES"
"2","(-7600,3350)","0","pure_quanta","I127";
;
PART_NUMBER"CS24702JB10"
VALUE"4.7K"
MATERIAL"EMPTY"
WATTAGE"1/16W"
TOLERANCE"5%"
PACK_TYPE"0402LF"
$LOCATION"R3451"
CDS_LIB"pure_quanta"
CDS_LOCATION"R3451"
$SEC"1"
CDS_SEC"1";
"A"
$PN"1"3;
"B"
$PN"2"39;
%"UNIVERSAL_GND"
"1","(-6225,1050)","0","logical_power","I137";
;
HDL_POWER"GND"
CDS_LIB"logical_power";
"A"14;
%"UNIVERSAL_GND"
"1","(-4950,750)","0","logical_power","I138";
;
HDL_POWER"GND"
CDS_LIB"logical_power";
"A"19;
%"Q_RES"
"2","(-4950,975)","0","pure_quanta","I139";
;
PART_NUMBER"CS31002FB08"
VALUE"10K"
PACK_TYPE"0402LF"
TOLERANCE"1%"
WATTAGE"1/16W"
MATERIAL"CHIP"
$LOCATION"R3455"
CDS_LIB"pure_quanta"
CDS_LOCATION"R3455"
$SEC"1"
CDS_SEC"1";
"A"
$PN"1"30;
"B"
$PN"2"19;
%"Q_CAP"
"1","(-6075,2175)","0","pure_quanta","I148";
;
PART_NUMBER"CH4104K1B00"
MATERIAL"X7R"
TOLERANCE"10%"
PACK_TYPE"0402"
VOLTAGE"25V"
VALUE"0.1UF"
$LOCATION"C1957"
CDS_LIB"pure_quanta"
CDS_LOCATION"C1957"
$SEC"1"
CDS_SEC"1";
"B"
$PN"2"15;
"A"
$PN"1"4;
%"UNIVERSAL_GND"
"1","(-6075,1950)","0","logical_power","I149";
;
HDL_POWER"GND"
CDS_LIB"logical_power";
"A"15;
%"74LVC2G17GW"
"1","(-6250,1575)","0","pure_quanta","I153";
;
PART_NUMBER"AL2G0017005"
MATERIAL"IC"
PART_TYPE"SMLF"
VALUE"74LVC2G17GW"
$LOCATION"U252"
CDS_LMAN_SYM_OUTLINE"-225,275,225,-275"
NEEDS_NO_SIZE"TRUE"
CDS_LIB"pure_quanta"
CDS_LOCATION"U252"
$SEC"1"
CDS_SEC"1";
"B0"
$PN"6"32;
"A1"
$PN"3"37;
"A0"
$PN"1"37;
"GND"
$PN"2"14;
"B1"
$PN"4"30;
"VCC"
$PN"5"4;
%"UNIVERSAL_POWER"
"1","(-6075,2500)","0","logical_power","I154";
;
HDL_POWER"P3V3_AUX"
CDS_LIB"logical_power";
"A"4;
%"UNIVERSAL_GND"
"1","(-7575,2625)","0","logical_power","I16";
;
HDL_POWER"GND"
CDS_LIB"logical_power";
"A"12;
%"UNIVERSAL_POWER"
"1","(-5000,4675)","0","logical_power","I163";
;
HDL_POWER"P3V3_AUX"
CDS_LIB"logical_power";
"A"9;
%"Q_RES"
"2","(-5000,4425)","0","pure_quanta","I164";
;
PART_NUMBER"CS41002FB09"
MATERIAL"EMPTY"
VALUE"100K"
TOLERANCE"1%"
WATTAGE"1/16W"
PACK_TYPE"0402LF"
$LOCATION"R3453"
CDS_LIB"pure_quanta"
CDS_LOCATION"R3453"
$SEC"1"
CDS_SEC"1";
"A"
$PN"1"9;
"B"
$PN"2"26;
%"Q_RES"
"2","(-4975,3825)","0","pure_quanta","I165";
;
PART_NUMBER"CS21002FB06"
WATTAGE"1/16W"
VALUE"1K"
TOLERANCE"1%"
MATERIAL"CHIP"
PACK_TYPE"0402LF"
$LOCATION"R3454"
CDS_LIB"pure_quanta"
CDS_LOCATION"R3454"
$SEC"1"
CDS_SEC"1";
"A"
$PN"1"26;
"B"
$PN"2"23;
%"UNIVERSAL_GND"
"1","(-4975,3625)","0","logical_power","I166";
;
CDS_LIB"logical_power"
HDL_POWER"GND";
"A"23;
%"UNIVERSAL_POWER"
"1","(-7600,4650)","0","logical_power","I167";
;
HDL_POWER"P3V3_AUX"
CDS_LIB"logical_power";
"A"7;
%"Q_RES"
"2","(-7600,4400)","0","pure_quanta","I168";
;
PART_NUMBER"CS24702JB10"
TOLERANCE"5%"
WATTAGE"1/16W"
PACK_TYPE"0402LF"
MATERIAL"EMPTY"
VALUE"4.7K"
$LOCATION"R3448"
CDS_LIB"pure_quanta"
CDS_LOCATION"R3448"
$SEC"1"
CDS_SEC"1";
"A"
$PN"1"7;
"B"
$PN"2"38;
%"Q_RES"
"2","(-7575,3925)","0","pure_quanta","I170";
;
PART_NUMBER"CS41002FB09"
VALUE"100K"
MATERIAL"CHIP"
TOLERANCE"1%"
PACK_TYPE"0402LF"
WATTAGE"1/16W"
$LOCATION"R3449"
CDS_LIB"pure_quanta"
CDS_LOCATION"R3449"
$SEC"1"
CDS_SEC"1";
"A"
$PN"1"38;
"B"
$PN"2"13;
%"UNIVERSAL_GND"
"1","(-7575,3725)","0","logical_power","I171";
;
HDL_POWER"GND"
CDS_LIB"logical_power";
"A"13;
%"74LVC2G17GW"
"1","(-6325,-275)","0","pure_quanta","I173";
;
PART_NUMBER"AL2G0017005"
MATERIAL"IC"
VALUE"74LVC2G17GW"
PART_TYPE"SMLF"
$LOCATION"U256"
CDS_LMAN_SYM_OUTLINE"-225,275,225,-275"
NEEDS_NO_SIZE"TRUE"
CDS_LIB"pure_quanta"
CDS_LOCATION"U256"
$SEC"1"
CDS_SEC"1";
"B0"
$PN"6"35;
"A1"
$PN"3"40;
"A0"
$PN"1"37;
"GND"
$PN"2"16;
"B1"
$PN"4"34;
"VCC"
$PN"5"5;
%"UNIVERSAL_POWER"
"1","(-6175,625)","0","logical_power","I174";
;
HDL_POWER"P3V3_AUX"
CDS_LIB"logical_power";
"A"5;
%"Q_CAP"
"1","(-6175,300)","0","pure_quanta","I175";
;
PART_NUMBER"CH4104K1B00"
VALUE"0.1UF"
MATERIAL"X7R"
TOLERANCE"10%"
VOLTAGE"25V"
PACK_TYPE"0402"
$LOCATION"C1977"
CDS_LIB"pure_quanta"
CDS_LOCATION"C1977"
$SEC"1"
CDS_SEC"1";
"B"
$PN"2"18;
"A"
$PN"1"5;
%"UNIVERSAL_GND"
"1","(-6175,75)","0","logical_power","I176";
;
HDL_POWER"GND"
CDS_LIB"logical_power";
"A"18;
%"UNIVERSAL_GND"
"1","(-6300,-850)","0","logical_power","I177";
;
CDS_LIB"logical_power"
HDL_POWER"GND";
"A"16;
%"UNIVERSAL_GND"
"1","(-4950,1400)","0","logical_power","I178";
;
CDS_LIB"logical_power"
HDL_POWER"GND";
"A"20;
%"Q_RES"
"2","(-4950,1625)","0","pure_quanta","I181";
;
PART_NUMBER"CS31002FB08"
VALUE"10K"
WATTAGE"1/16W"
PACK_TYPE"0402LF"
TOLERANCE"1%"
MATERIAL"CHIP"
$LOCATION"R3467"
CDS_LIB"pure_quanta"
CDS_LOCATION"R3467"
$SEC"1"
CDS_SEC"1";
"A"
$PN"1"32;
"B"
$PN"2"20;
%"Q_RES"
"2","(-4975,-175)","0","pure_quanta","I184";
;
PART_NUMBER"CS31002FB08"
MATERIAL"CHIP"
TOLERANCE"1%"
PACK_TYPE"0402LF"
VALUE"10K"
WATTAGE"1/16W"
$LOCATION"R3466"
CDS_LIB"pure_quanta"
CDS_LOCATION"R3466"
$SEC"1"
CDS_SEC"1";
"A"
$PN"1"35;
"B"
$PN"2"17;
%"UNIVERSAL_GND"
"1","(-4975,-400)","0","logical_power","I185";
;
HDL_POWER"GND"
CDS_LIB"logical_power";
"A"17;
%"UNIVERSAL_POWER"
"1","(-7800,125)","0","logical_power","I186";
;
HDL_POWER"P3V3_AUX"
CDS_LIB"logical_power";
"A"6;
%"Q_RES"
"2","(-7800,-125)","0","pure_quanta","I187";
;
PART_NUMBER"CS41002FB09"
MATERIAL"EMPTY"
PACK_TYPE"0402LF"
WATTAGE"1/16W"
VALUE"100K"
TOLERANCE"1%"
$LOCATION"R2910"
CDS_LIB"pure_quanta"
CDS_LOCATION"R2910"
$SEC"1"
CDS_SEC"1";
"A"
$PN"1"6;
"B"
$PN"2"40;
%"Q_RES"
"2","(-7775,-600)","0","pure_quanta","I188";
;
PART_NUMBER"CS24702JB10"
VALUE"4.7K"
MATERIAL"CHIP"
TOLERANCE"5%"
PACK_TYPE"0402LF"
WATTAGE"1/16W"
$LOCATION"R2918"
CDS_LIB"pure_quanta"
CDS_LOCATION"R2918"
$SEC"1"
CDS_SEC"1";
"A"
$PN"1"40;
"B"
$PN"2"11;
%"UNIVERSAL_GND"
"1","(-7775,-775)","0","logical_power","I189";
;
HDL_POWER"GND"
CDS_LIB"logical_power";
"A"11;
%"UNIVERSAL_POWER"
"1","(-4150,-50)","0","logical_power","I191";
;
HDL_POWER"P3V3_AUX"
CDS_LIB"logical_power";
"A"2;
%"Q_RES"
"2","(-4150,-300)","0","pure_quanta","I192";
;
PART_NUMBER"CS24702JB10"
VALUE"4.7K"
PACK_TYPE"0402LF"
MATERIAL"EMPTY"
WATTAGE"1/16W"
TOLERANCE"5%"
$LOCATION"R2914"
CDS_LIB"pure_quanta"
CDS_LOCATION"R2914"
$SEC"1"
CDS_SEC"1";
"A"
$PN"1"2;
"B"
$PN"2"34;
%"Q_RES"
"2","(-4125,-800)","0","pure_quanta","I195";
;
PART_NUMBER"CS24702JB10"
VALUE"4.7K"
TOLERANCE"5%"
MATERIAL"CHIP"
PACK_TYPE"0402LF"
WATTAGE"1/16W"
$LOCATION"R2932"
CDS_LIB"pure_quanta"
CDS_LOCATION"R2932"
$SEC"1"
CDS_SEC"1";
"A"
$PN"1"34;
"B"
$PN"2"10;
%"UNIVERSAL_GND"
"1","(-4125,-1025)","0","logical_power","I196";
;
HDL_POWER"GND"
CDS_LIB"logical_power";
"A"10;
%"Q_RES"
"1","(-4650,100)","0","pure_quanta","I197";
;
PART_NUMBER"CS04992FB07"
MATERIAL"CHIP"
VALUE"49.9"
LOCATION"R3468"
CDS_LIB"pure_quanta"
WATTAGE"1/16W"
TOLERANCE"1%"
PACK_TYPE"0402LF"
$SEC"1"
CDS_SEC"1";
"B"
$PN"2"36;
"A"
$PN"1"35;
%"Q_RES"
"1","(-3875,-525)","0","pure_quanta","I198";
;
PART_NUMBER"CS04992FB07"
MATERIAL"CHIP"
VALUE"49.9"
LOCATION"R3515"
CDS_LIB"pure_quanta"
WATTAGE"1/16W"
TOLERANCE"1%"
PACK_TYPE"0402LF"
$SEC"1"
CDS_SEC"1";
"B"
$PN"2"33;
"A"
$PN"1"34;
%"Q_RES"
"1","(-4625,1900)","0","pure_quanta","I199";
;
PART_NUMBER"CS04992FB07"
VALUE"49.9"
MATERIAL"CHIP"
LOCATION"R3469"
PACK_TYPE"0402LF"
TOLERANCE"1%"
WATTAGE"1/16W"
CDS_LIB"pure_quanta"
$SEC"1"
CDS_SEC"1";
"B"
$PN"2"29;
"A"
$PN"1"32;
%"UNIVERSAL_POWER"
"1","(-7600,3525)","0","logical_power","I20";
;
HDL_POWER"P3V3_AUX"
CDS_LIB"logical_power";
"A"3;
%"Q_RES"
"1","(-4625,1250)","0","pure_quanta","I200";
;
PART_NUMBER"CS04992FB07"
MATERIAL"CHIP"
VALUE"49.9"
LOCATION"R3391"
CDS_LIB"pure_quanta"
WATTAGE"1/16W"
TOLERANCE"1%"
PACK_TYPE"0402LF"
$SEC"1"
CDS_SEC"1";
"B"
$PN"2"31;
"A"
$PN"1"30;
%"Q_RES"
"1","(-4750,4125)","0","pure_quanta","I201";
;
PART_NUMBER"CS04992FB07"
VALUE"49.9"
MATERIAL"CHIP"
LOCATION"R3390"
CDS_LIB"pure_quanta"
WATTAGE"1/16W"
TOLERANCE"1%"
PACK_TYPE"0402LF"
$SEC"1"
CDS_SEC"1";
"B"
$PN"2"25;
"A"
$PN"1"26;
%"Q_RES"
"1","(-4625,3000)","0","pure_quanta","I202";
;
PART_NUMBER"CS04992FB07"
VALUE"49.9"
MATERIAL"CHIP"
LOCATION"R3392"
PACK_TYPE"0402LF"
TOLERANCE"1%"
WATTAGE"1/16W"
CDS_LIB"pure_quanta"
$SEC"1"
CDS_SEC"1";
"B"
$PN"2"28;
"A"
$PN"1"27;
%"74LVC2G17GW"
"1","(-6125,3575)","0","pure_quanta","I26";
;
PART_NUMBER"AL2G0017005"
PART_TYPE"SMLF"
VALUE"74LVC2G17GW"
MATERIAL"IC"
$LOCATION"U253"
CDS_LMAN_SYM_OUTLINE"-225,275,225,-275"
NEEDS_NO_SIZE"TRUE"
CDS_LIB"pure_quanta"
CDS_LOCATION"U253"
$SEC"1"
CDS_SEC"1";
"B0"
$PN"6"26;
"A1"
$PN"3"39;
"A0"
$PN"1"38;
"GND"
$PN"2"21;
"B1"
$PN"4"27;
"VCC"
$PN"5"8;
%"UNIVERSAL_GND"
"1","(-6100,2975)","0","logical_power","I27";
;
CDS_LIB"logical_power"
HDL_POWER"GND";
"A"21;
%"UNIVERSAL_GND"
"1","(-5975,4275)","0","logical_power","I28";
;
HDL_POWER"GND"
CDS_LIB"logical_power";
"A"24;
%"Q_CAP"
"1","(-5975,4500)","0","pure_quanta","I29";
;
PART_NUMBER"CH4104K1B00"
VALUE"0.1UF"
VOLTAGE"25V"
MATERIAL"X7R"
TOLERANCE"10%"
PACK_TYPE"0402"
$LOCATION"C1958"
CDS_LIB"pure_quanta"
CDS_LOCATION"C1958"
$SEC"1"
CDS_SEC"1";
"B"
$PN"2"24;
"A"
$PN"1"8;
%"UNIVERSAL_POWER"
"1","(-5975,4825)","0","logical_power","I30";
;
HDL_POWER"P3V3_AUX"
CDS_LIB"logical_power";
"A"8;
%"Q_RES"
"2","(-7575,2875)","0","pure_quanta","I95";
;
PART_NUMBER"CS41002FB09"
PACK_TYPE"0402LF"
MATERIAL"CHIP"
TOLERANCE"1%"
VALUE"100K"
WATTAGE"1/16W"
$LOCATION"R3452"
CDS_LIB"pure_quanta"
CDS_LOCATION"R3452"
$SEC"1"
CDS_SEC"1";
"A"
$PN"1"39;
"B"
$PN"2"12;
END.
